FILE_TYPE = MACRO_DRAWING;
SET COLOR_WIRE YELLOW;
SET COLOR_PROP MONO;
SET COLOR_DOT WHITE;
SET COLOR_ARC YELLOW;
SET COLOR_BODY GREEN;
SET COLOR_NOTE MONO;
SET PROP_DISPLAY VALUE;
SET PAGE_NUMBER P162;
FORCEADD P3V3_STBY..1
(4900 3725);
FORCEPROP 3 LASTPIN (4900 3675) SIG_NAME P3V3_STBY\g
J 0
(4910 3685);
DISPLAY 0.659574 (4910 3685);
PAINT MONO (4910 3685);
DISPLAY INVISIBLE (4910 3685);
FORCEPROP 1 LAST HDL_POWER P3V3_STBY
J 0
(4600 3600);
DISPLAY 0.872340 (4600 3600);
PAINT ORANGE (4600 3600);
DISPLAY INVISIBLE (4600 3600);
FORCEPROP 1 LAST PATH I10
J 0
(4945 3727);
DISPLAY 0.340426 (4945 3727);
PAINT GREEN (4945 3727);
DISPLAY INVISIBLE (4945 3727);
FORCEPROP 1 LAST BODY_TYPE PLUMBING
J 0
(4855 3682);
DISPLAY 0.340426 (4855 3682);
PAINT GREEN (4855 3682);
DISPLAY INVISIBLE (4855 3682);
FORCEPROP 1 LAST SIZE 1B
J 0
(4945 3747);
DISPLAY 0.340426 (4945 3747);
PAINT GREEN (4945 3747);
DISPLAY INVISIBLE (4945 3747);
FORCEPROP 2 LAST CDS_LIB mstr_symbols
J 0
(4900 3725);
PAINT ORANGE (4900 3725);
DISPLAY INVISIBLE (4900 3725);
FORCEPROP 1 LAST VOLTAGE 3.3V
J 0
(4855 3682);
DISPLAY 0.340426 (4855 3682);
PAINT SKYBLUE (4855 3682);
DISPLAY INVISIBLE (4855 3682);
FORCEADD RES..1
(5075 2550);
FORCEPROP 1 LAST LOCATION R8F12
J 0
(4768 2557);
DISPLAY 0.617021 (4768 2557);
PAINT AQUA (4768 2557);
FORCEPROP 1 LASTPIN (4975 2550) $PN 1
J 0
(4987 2562);
DISPLAY 0.617021 (4987 2562);
PAINT MONO (4987 2562);
FORCEPROP 1 LASTPIN (5175 2550) $PN 2
J 0
(5137 2562);
DISPLAY 0.617021 (5137 2562);
PAINT MONO (5137 2562);
FORCEPROP 1 LAST VALUE 33.2
J 2
(5300 2557);
DISPLAY 0.617021 (5300 2557);
PAINT SKYBLUE (5300 2557);
FORCEPROP 1 LAST WATTAGE 1/16W
J 2
(5050 2400);
PAINT SKYBLUE (5050 2400);
DISPLAY INVISIBLE (5050 2400);
FORCEPROP 2 LAST CDS_LOCATION R8F12
J 0
(4768 2557);
DISPLAY 0.617021 (4768 2557);
PAINT AQUA (4768 2557);
DISPLAY INVISIBLE (4768 2557);
FORCEPROP 2 LAST CDS_LIB mstr_discrete
J 1
(5075 2550);
PAINT ORANGE (5075 2550);
DISPLAY INVISIBLE (5075 2550);
FORCEPROP 1 LAST PART_NUMBER G21796-074
J 0
(5025 2650);
PAINT BLUE (5025 2650);
DISPLAY INVISIBLE (5025 2650);
FORCEPROP 2 LAST SEC_TYPE 0402
J 0
(5025 2775);
DISPLAY 1.021277 (5025 2775);
PAINT ORANGE (5025 2775);
DISPLAY INVISIBLE (5025 2775);
FORCEPROP 2 LAST SEC 1
J 0
(5025 2775);
DISPLAY 0.680851 (5025 2775);
PAINT MONO (5025 2775);
DISPLAY INVISIBLE (5025 2775);
FORCEPROP 1 LAST PATH I13
J 0
(5025 2700);
DISPLAY 0.978723 (5025 2700);
PAINT WHITE (5025 2700);
DISPLAY INVISIBLE (5025 2700);
FORCEPROP 2 LAST ROOM BMC_BOOT_SPI
J 0
(5300 2600);
DISPLAY 1.021277 (5300 2600);
PAINT ORANGE (5300 2600);
DISPLAY INVISIBLE (5300 2600);
FORCEPROP 2 LAST BOM_COST SM_MEM
J 0
(5300 2650);
DISPLAY 1.021277 (5300 2650);
PAINT ORANGE (5300 2650);
DISPLAY INVISIBLE (5300 2650);
FORCEPROP 1 LAST MATERIAL CHIP
J 0
(5275 2550);
PAINT SKYBLUE (5275 2550);
DISPLAY INVISIBLE (5275 2550);
FORCEPROP 1 LAST PACK_TYPE 0402
J 0
(5325 2400);
PAINT SKYBLUE (5325 2400);
DISPLAY INVISIBLE (5325 2400);
FORCEPROP 1 LAST TOLERANCE 1%
J 0
(5150 2400);
PAINT SKYBLUE (5150 2400);
DISPLAY INVISIBLE (5150 2400);
FORCEADD OFFPAGE..1
(4200 2850);
FORCEPROP 2 LAST $XR1 151 
J 0
(3948 2850);
DISPLAY 0.638298 (3948 2850);
PAINT MONO (3948 2850);
FORCEPROP 2 LAST $XR2 246 
J 0
(3723 2850);
DISPLAY 0.638298 (3723 2850);
PAINT MONO (3723 2850);
FORCEPROP 2 LAST $XR0 146 
J 0
(3848 2850);
DISPLAY 0.638298 (3848 2850);
PAINT MONO (3848 2850);
FORCEPROP 2 LAST PATH I16
J 0
(3950 2900);
DISPLAY 1.021277 (3950 2900);
PAINT ORANGE (3950 2900);
DISPLAY INVISIBLE (3950 2900);
FORCEPROP 1 LAST COMMENT_BODY TRUE
J 0
(4325 2750);
DISPLAY 0.978723 (4325 2750);
PAINT PEACH (4325 2750);
DISPLAY INVISIBLE (4325 2750);
FORCEPROP 2 LAST CDS_LIB mstr_standard
J 0
(4200 2850);
DISPLAY 1.531915 (4200 2850);
PAINT ORANGE (4200 2850);
DISPLAY INVISIBLE (4200 2850);
FORCEPROP 1 LAST OFFPAGE TRUE
J 0
(4525 2725);
PAINT GREEN (4525 2725);
DISPLAY INVISIBLE (4525 2725);
FORCEADD OFFPAGE..1
(4200 2800);
FORCEPROP 2 LAST $XR1 151 
J 0
(3948 2800);
DISPLAY 0.638298 (3948 2800);
PAINT MONO (3948 2800);
FORCEPROP 2 LAST $XR2 ?
J 0
(3723 2800);
DISPLAY 0.638298 (3723 2800);
PAINT MONO (3723 2800);
FORCEPROP 2 LAST $XR0 146 
J 0
(3823 2800);
DISPLAY 0.638298 (3823 2800);
PAINT MONO (3823 2800);
FORCEPROP 2 LAST PATH I17
J 0
(3950 2850);
DISPLAY 1.021277 (3950 2850);
PAINT ORANGE (3950 2850);
DISPLAY INVISIBLE (3950 2850);
FORCEPROP 1 LAST COMMENT_BODY TRUE
J 0
(4325 2700);
DISPLAY 0.978723 (4325 2700);
PAINT PEACH (4325 2700);
DISPLAY INVISIBLE (4325 2700);
FORCEPROP 2 LAST CDS_LIB mstr_standard
J 0
(4200 2800);
DISPLAY 1.531915 (4200 2800);
PAINT ORANGE (4200 2800);
DISPLAY INVISIBLE (4200 2800);
FORCEPROP 1 LAST OFFPAGE TRUE
J 0
(4525 2675);
PAINT GREEN (4525 2675);
DISPLAY INVISIBLE (4525 2675);
FORCEADD OFFPAGE..5
(4200 2550);
FORCEPROP 2 LAST $XR1 146 
J 0
(3945 2550);
DISPLAY 0.638298 (3945 2550);
PAINT MONO (3945 2550);
FORCEPROP 2 LAST $XR2 151 
J 0
(3845 2550);
DISPLAY 0.638298 (3845 2550);
PAINT MONO (3845 2550);
FORCEPROP 2 LAST $XR0 246 
J 0
(3745 2550);
DISPLAY 0.638298 (3745 2550);
PAINT MONO (3745 2550);
FORCEPROP 2 LAST PATH I19
J 0
(3925 2600);
DISPLAY 1.021277 (3925 2600);
PAINT ORANGE (3925 2600);
DISPLAY INVISIBLE (3925 2600);
FORCEPROP 1 LAST COMMENT_BODY TRUE
J 0
(4300 2475);
DISPLAY 1.170213 (4300 2475);
PAINT GREEN (4300 2475);
DISPLAY INVISIBLE (4300 2475);
FORCEPROP 1 LAST OFFPAGE TRUE
J 0
(4525 2425);
PAINT GREEN (4525 2425);
DISPLAY INVISIBLE (4525 2425);
FORCEPROP 2 LAST CDS_LIB mstr_standard
J 1
(4200 2550);
PAINT ORANGE (4200 2550);
DISPLAY INVISIBLE (4200 2550);
FORCEADD OFFPAGE..1
(4200 2500);
FORCEPROP 2 LAST $XR1 151 
J 0
(3948 2500);
DISPLAY 0.638298 (3948 2500);
PAINT MONO (3948 2500);
FORCEPROP 2 LAST $XR0 146 
J 0
(3848 2500);
DISPLAY 0.638298 (3848 2500);
PAINT MONO (3848 2500);
FORCEPROP 2 LAST $XR2 246 
J 0
(3723 2500);
DISPLAY 0.638298 (3723 2500);
PAINT MONO (3723 2500);
FORCEPROP 2 LAST PATH I21
J 0
(3925 2550);
DISPLAY 1.021277 (3925 2550);
PAINT ORANGE (3925 2550);
DISPLAY INVISIBLE (3925 2550);
FORCEPROP 1 LAST COMMENT_BODY TRUE
J 0
(4325 2400);
DISPLAY 0.978723 (4325 2400);
PAINT PEACH (4325 2400);
DISPLAY INVISIBLE (4325 2400);
FORCEPROP 1 LAST OFFPAGE TRUE
J 0
(4525 2375);
PAINT GREEN (4525 2375);
DISPLAY INVISIBLE (4525 2375);
FORCEPROP 2 LAST CDS_LIB mstr_standard
J 0
(4200 2500);
DISPLAY 1.531915 (4200 2500);
PAINT ORANGE (4200 2500);
DISPLAY INVISIBLE (4200 2500);
FORCEADD RES..2
R 2
(4825 3325);
FORCEPROP 1 LAST PART_NUMBER G21796-072
J 2
(4785 3200);
DISPLAY 0.617021 (4785 3200);
PAINT BLUE (4785 3200);
FORCEPROP 1 LAST PACK_TYPE 0402
J 2
(4785 3150);
DISPLAY 0.617021 (4785 3150);
PAINT SKYBLUE (4785 3150);
FORCEPROP 1 LAST TOLERANCE 1%
J 2
(4780 3300);
DISPLAY 0.617021 (4780 3300);
PAINT SKYBLUE (4780 3300);
FORCEPROP 1 LAST WATTAGE 1/16W
J 2
(4785 3250);
DISPLAY 0.617021 (4785 3250);
PAINT SKYBLUE (4785 3250);
FORCEPROP 1 LAST VALUE 4.75K
J 2
(4780 3400);
DISPLAY 0.617021 (4780 3400);
PAINT SKYBLUE (4780 3400);
FORCEPROP 1 LAST MATERIAL CHIP
J 2
(4785 3350);
DISPLAY 0.617021 (4785 3350);
PAINT SKYBLUE (4785 3350);
FORCEPROP 1 LAST LOCATION R8F34
J 2
(4780 3450);
DISPLAY 0.617021 (4780 3450);
PAINT AQUA (4780 3450);
FORCEPROP 1 LASTPIN (4825 3225) $PN 2
J 2
(4820 3235);
DISPLAY 0.787234 (4820 3235);
PAINT ORANGE (4820 3235);
DISPLAY INVISIBLE (4820 3235);
FORCEPROP 2 LAST CDS_LIB mstr_discrete
J 0
(4825 3325);
PAINT ORANGE (4825 3325);
DISPLAY INVISIBLE (4825 3325);
FORCEPROP 1 LASTPIN (4825 3425) $PN 1
J 2
(4820 3387);
DISPLAY 0.787234 (4820 3387);
PAINT ORANGE (4820 3387);
DISPLAY INVISIBLE (4820 3387);
FORCEPROP 2 LAST CDS_LOCATION R8F34
J 2
(4780 3450);
DISPLAY 0.617021 (4780 3450);
PAINT AQUA (4780 3450);
DISPLAY INVISIBLE (4780 3450);
FORCEPROP 1 LAST PATH I22
J 2
(4775 3500);
DISPLAY 0.978723 (4775 3500);
PAINT WHITE (4775 3500);
DISPLAY INVISIBLE (4775 3500);
FORCEPROP 2 LAST ROOM BMC_BOOT_SPI
J 0
(4800 3500);
DISPLAY 1.021277 (4800 3500);
PAINT ORANGE (4800 3500);
DISPLAY INVISIBLE (4800 3500);
FORCEPROP 2 LAST $SEC 1
J 0
(4775 3550);
PAINT MONO (4775 3550);
DISPLAY INVISIBLE (4775 3550);
FORCEPROP 2 LAST CDS_SEC 1
J 0
(4775 3550);
PAINT MONO (4775 3550);
DISPLAY INVISIBLE (4775 3550);
FORCEPROP 2 LAST BOM_COST SM_MEM
J 0
(4800 3550);
DISPLAY 1.021277 (4800 3550);
PAINT ORANGE (4800 3550);
DISPLAY INVISIBLE (4800 3550);
FORCEADD RES..2
R 2
(4550 3325);
FORCEPROP 1 LAST PART_NUMBER G21796-072
J 2
(4510 3200);
DISPLAY 0.617021 (4510 3200);
PAINT BLUE (4510 3200);
FORCEPROP 1 LAST PACK_TYPE 0402
J 2
(4510 3150);
DISPLAY 0.617021 (4510 3150);
PAINT SKYBLUE (4510 3150);
FORCEPROP 1 LAST TOLERANCE 1%
J 2
(4505 3300);
DISPLAY 0.617021 (4505 3300);
PAINT SKYBLUE (4505 3300);
FORCEPROP 1 LAST WATTAGE 1/16W
J 2
(4510 3250);
DISPLAY 0.617021 (4510 3250);
PAINT SKYBLUE (4510 3250);
FORCEPROP 1 LAST LOCATION R8F13
J 2
(4505 3450);
DISPLAY 0.617021 (4505 3450);
PAINT AQUA (4505 3450);
FORCEPROP 1 LAST MATERIAL CHIP
J 2
(4510 3350);
DISPLAY 0.617021 (4510 3350);
PAINT SKYBLUE (4510 3350);
FORCEPROP 1 LAST VALUE 4.75K
J 2
(4505 3400);
DISPLAY 0.617021 (4505 3400);
PAINT SKYBLUE (4505 3400);
FORCEPROP 1 LASTPIN (4550 3225) $PN 2
J 2
(4545 3235);
DISPLAY 0.787234 (4545 3235);
PAINT ORANGE (4545 3235);
DISPLAY INVISIBLE (4545 3235);
FORCEPROP 2 LAST CDS_LIB mstr_discrete
J 0
(4550 3325);
PAINT ORANGE (4550 3325);
DISPLAY INVISIBLE (4550 3325);
FORCEPROP 1 LASTPIN (4550 3425) $PN 1
J 2
(4545 3387);
DISPLAY 0.787234 (4545 3387);
PAINT ORANGE (4545 3387);
DISPLAY INVISIBLE (4545 3387);
FORCEPROP 2 LAST ROOM BMC_BOOT_SPI
J 0
(4525 3500);
DISPLAY 1.021277 (4525 3500);
PAINT ORANGE (4525 3500);
DISPLAY INVISIBLE (4525 3500);
FORCEPROP 1 LAST PATH I23
J 2
(4500 3500);
DISPLAY 0.978723 (4500 3500);
PAINT WHITE (4500 3500);
DISPLAY INVISIBLE (4500 3500);
FORCEPROP 2 LAST CDS_LOCATION R8F13
J 2
(4505 3450);
DISPLAY 0.617021 (4505 3450);
PAINT AQUA (4505 3450);
DISPLAY INVISIBLE (4505 3450);
FORCEPROP 2 LAST BOM_COST SM_MEM
J 0
(4525 3550);
DISPLAY 1.021277 (4525 3550);
PAINT ORANGE (4525 3550);
DISPLAY INVISIBLE (4525 3550);
FORCEPROP 2 LAST CDS_SEC 1
J 0
(4500 3550);
PAINT MONO (4500 3550);
DISPLAY INVISIBLE (4500 3550);
FORCEPROP 2 LAST $SEC 1
J 0
(4500 3550);
PAINT MONO (4500 3550);
DISPLAY INVISIBLE (4500 3550);
FORCEADD RES..2
(4875 2050);
FORCEPROP 1 LAST PACK_TYPE 0402
J 0
(4915 1875);
DISPLAY 0.617021 (4915 1875);
PAINT SKYBLUE (4915 1875);
FORCEPROP 1 LAST MATERIAL EMPTY
J 0
(4915 1975);
DISPLAY 0.617021 (4915 1975);
PAINT RED (4915 1975);
FORCEPROP 1 LAST PART_NUMBER G21796-026
J 0
(4915 1925);
DISPLAY 0.617021 (4915 1925);
PAINT BLUE (4915 1925);
FORCEPROP 1 LAST WATTAGE 1/16W
J 0
(4915 2025);
DISPLAY 0.617021 (4915 2025);
PAINT SKYBLUE (4915 2025);
FORCEPROP 1 LAST TOLERANCE 1%
J 0
(4920 2075);
DISPLAY 0.617021 (4920 2075);
PAINT SKYBLUE (4920 2075);
FORCEPROP 1 LAST VALUE 1.00K
J 0
(4920 2125);
DISPLAY 0.617021 (4920 2125);
PAINT SKYBLUE (4920 2125);
FORCEPROP 1 LAST LOCATION R8F35
J 0
(4920 2175);
DISPLAY 0.617021 (4920 2175);
PAINT AQUA (4920 2175);
FORCEPROP 1 LASTPIN (4875 1950) $PN 2
J 0
(4880 1960);
DISPLAY 0.787234 (4880 1960);
PAINT ORANGE (4880 1960);
DISPLAY INVISIBLE (4880 1960);
FORCEPROP 1 LASTPIN (4875 2150) $PN 1
J 0
(4880 2112);
DISPLAY 0.787234 (4880 2112);
PAINT ORANGE (4880 2112);
DISPLAY INVISIBLE (4880 2112);
FORCEPROP 2 LAST CDS_LIB mstr_discrete
J 0
(4875 2050);
PAINT ORANGE (4875 2050);
DISPLAY INVISIBLE (4875 2050);
FORCEPROP 2 LAST CDS_LOCATION R8F35
J 0
(4920 2175);
DISPLAY 0.617021 (4920 2175);
PAINT AQUA (4920 2175);
DISPLAY INVISIBLE (4920 2175);
FORCEPROP 2 LAST ROOM BMC_BOOT_SPI
J 0
(4925 2225);
DISPLAY 1.021277 (4925 2225);
PAINT ORANGE (4925 2225);
DISPLAY INVISIBLE (4925 2225);
FORCEPROP 1 LAST PATH I24
J 0
(4925 2225);
DISPLAY 0.978723 (4925 2225);
PAINT WHITE (4925 2225);
DISPLAY INVISIBLE (4925 2225);
FORCEPROP 2 LAST $SEC 1
J 0
(4925 2275);
PAINT MONO (4925 2275);
DISPLAY INVISIBLE (4925 2275);
FORCEPROP 2 LAST CDS_SEC 1
J 0
(4925 2275);
PAINT MONO (4925 2275);
DISPLAY INVISIBLE (4925 2275);
FORCEPROP 2 LAST BOM_COST SM_MEM
J 0
(4925 2275);
DISPLAY 1.021277 (4925 2275);
PAINT ORANGE (4925 2275);
DISPLAY INVISIBLE (4925 2275);
FORCEADD CAP_A..1
(7650 3400);
FORCEPROP 1 LAST MATERIAL X7R
J 0
(7700 3300);
DISPLAY 0.617021 (7700 3300);
PAINT SKYBLUE (7700 3300);
FORCEPROP 1 LAST LOCATION C8F5
J 0
(7700 3500);
DISPLAY 0.617021 (7700 3500);
PAINT AQUA (7700 3500);
FORCEPROP 1 LAST PART_NUMBER A36096-045
J 0
(7700 3250);
DISPLAY 0.617021 (7700 3250);
PAINT BLUE (7700 3250);
FORCEPROP 1 LAST VALUE 0.01UF
J 0
(7700 3450);
DISPLAY 0.617021 (7700 3450);
PAINT SKYBLUE (7700 3450);
FORCEPROP 1 LAST TOLERANCE 10%
J 0
(7700 3350);
DISPLAY 0.617021 (7700 3350);
PAINT SKYBLUE (7700 3350);
FORCEPROP 1 LAST PACK_TYPE 0402V
J 0
(7700 3200);
DISPLAY 0.617021 (7700 3200);
PAINT SKYBLUE (7700 3200);
FORCEPROP 1 LAST VOLTAGE 25V
J 0
(7700 3400);
DISPLAY 0.617021 (7700 3400);
PAINT SKYBLUE (7700 3400);
FORCEPROP 1 LASTPIN (7650 3300) $PN 2
J 0
(7660 3280);
DISPLAY 0.787234 (7660 3280);
PAINT ORANGE (7660 3280);
DISPLAY INVISIBLE (7660 3280);
FORCEPROP 1 LASTPIN (7650 3500) $PN 1
J 0
(7660 3480);
DISPLAY 0.787234 (7660 3480);
PAINT ORANGE (7660 3480);
DISPLAY INVISIBLE (7660 3480);
FORCEPROP 2 LAST CDS_LIB dev_discrete
J 0
(7650 3400);
PAINT ORANGE (7650 3400);
DISPLAY INVISIBLE (7650 3400);
FORCEPROP 2 LAST CDS_LOCATION C8F5
J 0
(7700 3500);
DISPLAY 0.617021 (7700 3500);
PAINT AQUA (7700 3500);
DISPLAY INVISIBLE (7700 3500);
FORCEPROP 2 LAST ROOM BMC_BOOT_SPI
J 0
(7700 3550);
DISPLAY 1.021277 (7700 3550);
PAINT ORANGE (7700 3550);
DISPLAY INVISIBLE (7700 3550);
FORCEPROP 1 LAST PATH I28
J 0
(7700 3550);
DISPLAY 0.978723 (7700 3550);
PAINT WHITE (7700 3550);
DISPLAY INVISIBLE (7700 3550);
FORCEPROP 2 LAST CDS_SEC 1
J 0
(7700 3600);
PAINT MONO (7700 3600);
DISPLAY INVISIBLE (7700 3600);
FORCEPROP 2 LAST $SEC 1
J 0
(7700 3600);
PAINT MONO (7700 3600);
DISPLAY INVISIBLE (7700 3600);
FORCEPROP 2 LAST BOM_COST SM_MEM
J 0
(7700 3600);
DISPLAY 1.021277 (7700 3600);
PAINT ORANGE (7700 3600);
DISPLAY INVISIBLE (7700 3600);
FORCEADD CAP_A..1
(7350 3400);
FORCEPROP 1 LAST MATERIAL X6S
J 0
(7400 3300);
DISPLAY 0.617021 (7400 3300);
PAINT SKYBLUE (7400 3300);
FORCEPROP 1 LAST VOLTAGE 6.3V
J 0
(7400 3400);
DISPLAY 0.617021 (7400 3400);
PAINT SKYBLUE (7400 3400);
FORCEPROP 1 LAST PACK_TYPE 0402V
J 0
(7400 3200);
DISPLAY 0.617021 (7400 3200);
PAINT SKYBLUE (7400 3200);
FORCEPROP 1 LAST TOLERANCE 10%
J 0
(7400 3350);
DISPLAY 0.617021 (7400 3350);
PAINT SKYBLUE (7400 3350);
FORCEPROP 1 LAST VALUE 1.0UF
J 0
(7400 3450);
DISPLAY 0.617021 (7400 3450);
PAINT SKYBLUE (7400 3450);
FORCEPROP 1 LAST LOCATION C8F4
J 0
(7400 3500);
DISPLAY 0.617021 (7400 3500);
PAINT AQUA (7400 3500);
FORCEPROP 1 LAST PART_NUMBER D97712-004
J 0
(7400 3250);
DISPLAY 0.617021 (7400 3250);
PAINT BLUE (7400 3250);
FORCEPROP 1 LASTPIN (7350 3300) $PN 2
J 0
(7360 3280);
DISPLAY 0.787234 (7360 3280);
PAINT ORANGE (7360 3280);
DISPLAY INVISIBLE (7360 3280);
FORCEPROP 2 LAST CDS_LIB dev_discrete
J 0
(7350 3400);
PAINT ORANGE (7350 3400);
DISPLAY INVISIBLE (7350 3400);
FORCEPROP 2 LAST CDS_LOCATION C8F4
J 0
(7400 3500);
DISPLAY 0.617021 (7400 3500);
PAINT AQUA (7400 3500);
DISPLAY INVISIBLE (7400 3500);
FORCEPROP 1 LASTPIN (7350 3500) $PN 1
J 0
(7360 3480);
DISPLAY 0.787234 (7360 3480);
PAINT ORANGE (7360 3480);
DISPLAY INVISIBLE (7360 3480);
FORCEPROP 2 LAST ROOM BMC_BOOT_SPI
J 0
(7400 3550);
DISPLAY 1.021277 (7400 3550);
PAINT ORANGE (7400 3550);
DISPLAY INVISIBLE (7400 3550);
FORCEPROP 1 LAST PATH I30
J 0
(7400 3550);
DISPLAY 0.978723 (7400 3550);
PAINT WHITE (7400 3550);
DISPLAY INVISIBLE (7400 3550);
FORCEPROP 2 LAST $SEC 1
J 0
(7400 3600);
PAINT MONO (7400 3600);
DISPLAY INVISIBLE (7400 3600);
FORCEPROP 2 LAST CDS_SEC 1
J 0
(7400 3600);
PAINT MONO (7400 3600);
DISPLAY INVISIBLE (7400 3600);
FORCEPROP 2 LAST BOM_COST SM_MEM
J 0
(7400 3600);
DISPLAY 1.021277 (7400 3600);
PAINT ORANGE (7400 3600);
DISPLAY INVISIBLE (7400 3600);
FORCEADD GND..1
(7650 3075);
FORCEPROP 3 LASTPIN (7650 3125) SIG_NAME GND\g
J 0
(7660 3135);
DISPLAY 0.659574 (7660 3135);
PAINT MONO (7660 3135);
DISPLAY INVISIBLE (7660 3135);
FORCEPROP 1 LAST VOLTAGE 0.0V
J 0
(7605 3032);
DISPLAY 0.340426 (7605 3032);
PAINT SKYBLUE (7605 3032);
DISPLAY INVISIBLE (7605 3032);
FORCEPROP 1 LAST BODY_TYPE PLUMBING
J 0
(7605 3032);
DISPLAY 0.340426 (7605 3032);
PAINT GREEN (7605 3032);
DISPLAY INVISIBLE (7605 3032);
FORCEPROP 1 LAST SIZE 1B
J 0
(7725 3025);
DISPLAY 0.872340 (7725 3025);
PAINT AQUA (7725 3025);
DISPLAY INVISIBLE (7725 3025);
FORCEPROP 2 LAST CDS_LIB mstr_symbols
J 0
(7650 3075);
PAINT ORANGE (7650 3075);
DISPLAY INVISIBLE (7650 3075);
FORCEPROP 1 LAST HDL_POWER GND
J 0
(7650 3225);
DISPLAY 0.872340 (7650 3225);
PAINT GREEN (7650 3225);
DISPLAY INVISIBLE (7650 3225);
FORCEPROP 1 LAST PATH I31
J 0
(7725 3075);
DISPLAY 0.872340 (7725 3075);
PAINT AQUA (7725 3075);
DISPLAY INVISIBLE (7725 3075);
FORCEADD W25Q128..3
(6450 2800);
FORCEPROP 2 LASTPIN (5900 2500) $PN 15
J 2
(5890 2510);
DISPLAY 0.617021 (5890 2510);
PAINT ORANGE (5890 2510);
FORCEPROP 2 LASTPIN (5900 2550) $PN 8
J 2
(5890 2560);
DISPLAY 0.617021 (5890 2560);
PAINT ORANGE (5890 2560);
FORCEPROP 2 LASTPIN (5900 2800) $PN 7
J 2
(5890 2810);
DISPLAY 0.617021 (5890 2810);
PAINT ORANGE (5890 2810);
FORCEPROP 2 LASTPIN (5900 2900) $PN 3
J 2
(5890 2910);
DISPLAY 0.617021 (5890 2910);
PAINT ORANGE (5890 2910);
FORCEPROP 2 LASTPIN (5900 3000) $PN 2
J 2
(5890 3010);
DISPLAY 0.617021 (5890 3010);
PAINT ORANGE (5890 3010);
FORCEPROP 2 LASTPIN (5900 2600) $PN 9
J 2
(5890 2610);
DISPLAY 0.617021 (5890 2610);
PAINT ORANGE (5890 2610);
FORCEPROP 2 LASTPIN (5900 2650) $PN 1
J 2
(5890 2660);
DISPLAY 0.617021 (5890 2660);
PAINT ORANGE (5890 2660);
FORCEPROP 2 LASTPIN (5900 2850) $PN 16
J 2
(5890 2860);
DISPLAY 0.617021 (5890 2860);
PAINT ORANGE (5890 2860);
FORCEPROP 1 LAST MATERIAL IC
J 0
(5950 3150);
DISPLAY 0.617021 (5950 3150);
PAINT SKYBLUE (5950 3150);
FORCEPROP 1 LAST LOCATION U8F2
J 0
(5950 3200);
DISPLAY 0.617021 (5950 3200);
PAINT AQUA (5950 3200);
FORCEPROP 1 LAST PART_NUMBER H12709-001
J 0
(5950 2425);
DISPLAY 0.617021 (5950 2425);
PAINT BLUE (5950 2425);
FORCEPROP 2 LASTPIN (7000 2550) $PN 10
J 0
(7010 2560);
DISPLAY 0.617021 (7010 2560);
PAINT ORANGE (7010 2560);
FORCEPROP 2 LASTPIN (7000 2650) $PN 4
J 0
(7010 2660);
DISPLAY 0.617021 (7010 2660);
PAINT ORANGE (7010 2660);
FORCEPROP 2 LASTPIN (7000 2700) $PN 5
J 0
(7010 2710);
DISPLAY 0.617021 (7010 2710);
PAINT ORANGE (7010 2710);
FORCEPROP 2 LASTPIN (7000 2750) $PN 6
J 0
(7010 2760);
DISPLAY 0.617021 (7010 2760);
PAINT ORANGE (7010 2760);
FORCEPROP 2 LASTPIN (7000 2800) $PN 11
J 0
(7010 2810);
DISPLAY 0.617021 (7010 2810);
PAINT ORANGE (7010 2810);
FORCEPROP 2 LASTPIN (7000 2850) $PN 12
J 0
(7010 2860);
DISPLAY 0.617021 (7010 2860);
PAINT ORANGE (7010 2860);
FORCEPROP 2 LASTPIN (7000 2900) $PN 13
J 0
(7010 2910);
DISPLAY 0.617021 (7010 2910);
PAINT ORANGE (7010 2910);
FORCEPROP 2 LASTPIN (7000 2950) $PN 14
J 0
(7010 2960);
DISPLAY 0.617021 (7010 2960);
PAINT ORANGE (7010 2960);
FORCEPROP 0 LAST ROOM BMC_BOOT_SPI
J 0
(5950 3300);
DISPLAY 1.021277 (5950 3300);
PAINT ORANGE (5950 3300);
DISPLAY INVISIBLE (5950 3300);
FORCEPROP 2 LAST CDS_LOCATION U8F2
J 0
(5950 3200);
DISPLAY 0.617021 (5950 3200);
PAINT AQUA (5950 3200);
DISPLAY INVISIBLE (5950 3200);
FORCEPROP 2 LAST SEC 1
J 0
(5950 3250);
DISPLAY 0.680851 (5950 3250);
PAINT MONO (5950 3250);
DISPLAY INVISIBLE (5950 3250);
FORCEPROP 0 LAST BOM_COST SM_MEM
J 0
(5950 3400);
DISPLAY 1.021277 (5950 3400);
PAINT ORANGE (5950 3400);
DISPLAY INVISIBLE (5950 3400);
FORCEPROP 2 LAST SEC_TYPE SKT16
J 0
(5950 3250);
DISPLAY 1.021277 (5950 3250);
PAINT ORANGE (5950 3250);
DISPLAY INVISIBLE (5950 3250);
FORCEPROP 1 LAST PACK_TYPE SKT16
J 0
(5950 3250);
PAINT SKYBLUE (5950 3250);
DISPLAY INVISIBLE (5950 3250);
FORCEPROP 1 LAST CDS_LMAN_SYM_OUTLINE -500,325,500,-325
J 0
(6450 2800);
DISPLAY 0.468085 (6450 2800);
PAINT GREEN (6450 2800);
DISPLAY INVISIBLE (6450 2800);
FORCEPROP 2 LAST CDS_LIB mstr_memory
J 0
(6450 2800);
PAINT ORANGE (6450 2800);
DISPLAY INVISIBLE (6450 2800);
FORCEPROP 1 LAST PATH I32
J 0
(6825 3151);
PAINT GREEN (6825 3151);
DISPLAY INVISIBLE (6825 3151);
FORCEADD GND..1
(4875 1750);
FORCEPROP 3 LASTPIN (4875 1800) SIG_NAME GND\g
J 0
(4885 1810);
DISPLAY 0.659574 (4885 1810);
PAINT MONO (4885 1810);
DISPLAY INVISIBLE (4885 1810);
FORCEPROP 1 LAST BODY_TYPE PLUMBING
J 0
(4830 1707);
DISPLAY 0.340426 (4830 1707);
PAINT GREEN (4830 1707);
DISPLAY INVISIBLE (4830 1707);
FORCEPROP 1 LAST VOLTAGE 0.0V
J 0
(4830 1707);
DISPLAY 0.340426 (4830 1707);
PAINT SKYBLUE (4830 1707);
DISPLAY INVISIBLE (4830 1707);
FORCEPROP 1 LAST PATH I33
J 0
(4950 1750);
DISPLAY 0.872340 (4950 1750);
PAINT AQUA (4950 1750);
DISPLAY INVISIBLE (4950 1750);
FORCEPROP 2 LAST CDS_LIB mstr_symbols
J 0
(4875 1750);
PAINT ORANGE (4875 1750);
DISPLAY INVISIBLE (4875 1750);
FORCEPROP 1 LAST SIZE 1B
J 0
(4950 1700);
DISPLAY 0.872340 (4950 1700);
PAINT AQUA (4950 1700);
DISPLAY INVISIBLE (4950 1700);
FORCEPROP 1 LAST HDL_POWER GND
J 0
(4875 1900);
DISPLAY 0.872340 (4875 1900);
PAINT GREEN (4875 1900);
DISPLAY INVISIBLE (4875 1900);
FORCEADD GND..1
(7100 2350);
FORCEPROP 3 LASTPIN (7100 2400) SIG_NAME GND\g
J 0
(7110 2410);
DISPLAY 0.659574 (7110 2410);
PAINT MONO (7110 2410);
DISPLAY INVISIBLE (7110 2410);
FORCEPROP 1 LAST VOLTAGE 0
J 0
(7100 2350);
PAINT SKYBLUE (7100 2350);
DISPLAY INVISIBLE (7100 2350);
FORCEPROP 2 LAST CDS_LIB mstr_symbols
J 0
(7100 2350);
PAINT ORANGE (7100 2350);
DISPLAY INVISIBLE (7100 2350);
FORCEPROP 1 LAST BODY_TYPE PLUMBING
J 0
(7055 2307);
DISPLAY 0.340426 (7055 2307);
PAINT GREEN (7055 2307);
DISPLAY INVISIBLE (7055 2307);
FORCEPROP 1 LAST HDL_POWER GND
J 0
(7100 2500);
DISPLAY 1.170213 (7100 2500);
PAINT GREEN (7100 2500);
DISPLAY INVISIBLE (7100 2500);
FORCEPROP 1 LAST SIZE 1B
J 0
(7175 2300);
DISPLAY 1.170213 (7175 2300);
PAINT GREEN (7175 2300);
DISPLAY INVISIBLE (7175 2300);
FORCEPROP 1 LAST PATH I6
J 0
(7175 2350);
DISPLAY 0.872340 (7175 2350);
PAINT AQUA (7175 2350);
DISPLAY INVISIBLE (7175 2350);
FORCEADD RES..2
(5300 3300);
FORCEPROP 1 LASTPIN (5300 3200) $PN 2
J 0
(5305 3210);
DISPLAY 0.617021 (5305 3210);
PAINT ORANGE (5305 3210);
FORCEPROP 1 LASTPIN (5300 3400) $PN 1
J 0
(5305 3362);
DISPLAY 0.617021 (5305 3362);
PAINT ORANGE (5305 3362);
FORCEPROP 1 LAST PART_NUMBER G21796-072
J 0
(5340 3175);
DISPLAY 0.617021 (5340 3175);
PAINT BLUE (5340 3175);
FORCEPROP 1 LAST WATTAGE 1/16W
J 0
(5340 3225);
DISPLAY 0.617021 (5340 3225);
PAINT SKYBLUE (5340 3225);
FORCEPROP 1 LAST PACK_TYPE 0402
J 0
(5340 3125);
DISPLAY 0.617021 (5340 3125);
PAINT SKYBLUE (5340 3125);
FORCEPROP 1 LAST LOCATION R8F16
J 0
(5345 3425);
DISPLAY 0.617021 (5345 3425);
PAINT AQUA (5345 3425);
FORCEPROP 1 LAST MATERIAL EMPTY
J 0
(5340 3325);
DISPLAY 0.617021 (5340 3325);
PAINT RED (5340 3325);
FORCEPROP 1 LAST TOLERANCE 1%
J 0
(5345 3275);
DISPLAY 0.617021 (5345 3275);
PAINT SKYBLUE (5345 3275);
FORCEPROP 1 LAST VALUE 4.75K
J 0
(5395 3375);
DISPLAY 0.617021 (5395 3375);
PAINT SKYBLUE (5395 3375);
FORCEPROP 2 LAST CDS_LIB mstr_discrete
J 2
(5300 3300);
PAINT ORANGE (5300 3300);
DISPLAY INVISIBLE (5300 3300);
FORCEPROP 2 LAST CDS_LOCATION R8F16
J 0
(5345 3425);
DISPLAY 0.617021 (5345 3425);
PAINT AQUA (5345 3425);
DISPLAY INVISIBLE (5345 3425);
FORCEPROP 2 LAST ROOM BMC_BOOT_SPI
J 2
(5325 3475);
DISPLAY 1.021277 (5325 3475);
PAINT ORANGE (5325 3475);
DISPLAY INVISIBLE (5325 3475);
FORCEPROP 1 LAST PATH I8
J 0
(5350 3475);
DISPLAY 0.978723 (5350 3475);
PAINT WHITE (5350 3475);
DISPLAY INVISIBLE (5350 3475);
FORCEPROP 2 LAST SEC 1
J 2
(5350 3525);
DISPLAY 0.680851 (5350 3525);
PAINT MONO (5350 3525);
DISPLAY INVISIBLE (5350 3525);
FORCEPROP 2 LAST BOM_COST SM_MEM
J 2
(5325 3525);
DISPLAY 1.021277 (5325 3525);
PAINT ORANGE (5325 3525);
DISPLAY INVISIBLE (5325 3525);
FORCEPROP 2 LAST SEC_TYPE 0402
J 2
(5350 3525);
DISPLAY 1.021277 (5350 3525);
PAINT ORANGE (5350 3525);
DISPLAY INVISIBLE (5350 3525);
FORCEADD RES..2
R 2
(5100 3325);
FORCEPROP 1 LAST PART_NUMBER G21796-072
J 2
(5060 3200);
DISPLAY 0.617021 (5060 3200);
PAINT BLUE (5060 3200);
FORCEPROP 1 LASTPIN (5100 3225) $PN 2
J 2
(5095 3235);
DISPLAY 0.617021 (5095 3235);
PAINT ORANGE (5095 3235);
FORCEPROP 1 LAST WATTAGE 1/16W
J 2
(5060 3250);
DISPLAY 0.617021 (5060 3250);
PAINT SKYBLUE (5060 3250);
FORCEPROP 1 LAST TOLERANCE 1%
J 2
(5055 3300);
DISPLAY 0.617021 (5055 3300);
PAINT SKYBLUE (5055 3300);
FORCEPROP 1 LAST PACK_TYPE 0402
J 2
(5060 3150);
DISPLAY 0.617021 (5060 3150);
PAINT SKYBLUE (5060 3150);
FORCEPROP 1 LAST VALUE 4.75K
J 2
(5055 3400);
DISPLAY 0.617021 (5055 3400);
PAINT SKYBLUE (5055 3400);
FORCEPROP 1 LAST LOCATION R8F14
J 2
(5055 3450);
DISPLAY 0.617021 (5055 3450);
PAINT AQUA (5055 3450);
FORCEPROP 1 LAST MATERIAL CHIP
J 2
(5060 3350);
DISPLAY 0.617021 (5060 3350);
PAINT SKYBLUE (5060 3350);
FORCEPROP 1 LASTPIN (5100 3425) $PN 1
J 2
(5095 3387);
DISPLAY 0.617021 (5095 3387);
PAINT ORANGE (5095 3387);
FORCEPROP 2 LAST CDS_LIB mstr_discrete
J 0
(5100 3325);
PAINT ORANGE (5100 3325);
DISPLAY INVISIBLE (5100 3325);
FORCEPROP 2 LAST CDS_LOCATION R8F14
J 2
(5055 3450);
DISPLAY 0.617021 (5055 3450);
PAINT AQUA (5055 3450);
DISPLAY INVISIBLE (5055 3450);
FORCEPROP 2 LAST SEC 1
J 0
(5050 3550);
DISPLAY 0.680851 (5050 3550);
PAINT MONO (5050 3550);
DISPLAY INVISIBLE (5050 3550);
FORCEPROP 1 LAST PATH I9
J 2
(5050 3500);
DISPLAY 0.978723 (5050 3500);
PAINT WHITE (5050 3500);
DISPLAY INVISIBLE (5050 3500);
FORCEPROP 2 LAST ROOM BMC_BOOT_SPI
J 0
(5075 3500);
DISPLAY 1.021277 (5075 3500);
PAINT ORANGE (5075 3500);
DISPLAY INVISIBLE (5075 3500);
FORCEPROP 2 LAST BOM_COST SM_MEM
J 0
(5075 3550);
DISPLAY 1.021277 (5075 3550);
PAINT ORANGE (5075 3550);
DISPLAY INVISIBLE (5075 3550);
FORCEPROP 2 LAST SEC_TYPE 0402
J 0
(5050 3550);
DISPLAY 1.021277 (5050 3550);
PAINT ORANGE (5050 3550);
DISPLAY INVISIBLE (5050 3550);
FORCEADD DNS..2
(4880 2045);
PAINT RED (4880 2045);
FORCEPROP 1 LAST COMMENT_BODY TRUE
R 1
J 0
(4955 1820);
DISPLAY 0.872340 (4955 1820);
PAINT GREEN (4955 1820);
DISPLAY INVISIBLE (4955 1820);
FORCEPROP 2 LAST CDS_LIB mstr_misc
J 0
(4880 2045);
PAINT ORANGE (4880 2045);
DISPLAY INVISIBLE (4880 2045);
FORCEADD BOM_NOTE..1
(8075 2550);
FORCEPROP 0 LAST L1 SOCKET IS D91187-001
J 0
(7925 2450);
DISPLAY 0.617021 (7925 2450);
PAINT WHITE (7925 2450);
FORCEPROP 2 LAST CDS_LIB mstr_symbols
J 0
(8075 2550);
PAINT WHITE (8075 2550);
DISPLAY INVISIBLE (8075 2550);
FORCEPROP 1 LAST COMMENT_BODY TRUE
J 0
(8100 2650);
DISPLAY 1.319149 (8100 2650);
PAINT WHITE (8100 2650);
DISPLAY INVISIBLE (8100 2650);
FORCEADD CAD_NOTE..1
(8075 2850);
FORCEPROP 0 LAST L1 THIS PART WILL BE IN SOCKET, PLEASE
J 0
(7925 2750);
DISPLAY 0.617021 (7925 2750);
PAINT WHITE (7925 2750);
FORCEPROP 0 LAST L2 USE ALT SYMBOL ASSOCIATED WITH PART FOOTPRINT
J 0
(7925 2700);
DISPLAY 0.617021 (7925 2700);
PAINT WHITE (7925 2700);
FORCEPROP 2 LAST CDS_LIB mstr_symbols
J 0
(8075 2850);
PAINT WHITE (8075 2850);
DISPLAY INVISIBLE (8075 2850);
FORCEPROP 1 LAST COMMENT_BODY TRUE
J 0
(8100 2950);
DISPLAY 1.319149 (8100 2950);
PAINT WHITE (8100 2950);
DISPLAY INVISIBLE (8100 2950);
FORCEADD DNS..2
(5305 3295);
PAINT RED (5305 3295);
FORCEPROP 1 LAST COMMENT_BODY TRUE
R 1
J 0
(5380 3070);
DISPLAY 0.872340 (5380 3070);
PAINT GREEN (5380 3070);
DISPLAY INVISIBLE (5380 3070);
FORCEPROP 2 LAST CDS_LIB mstr_misc
J 0
(5305 3295);
PAINT ORANGE (5305 3295);
DISPLAY INVISIBLE (5305 3295);
FORCEADD CAD_NOTE..1
(8075 3425);
FORCEPROP 0 LAST L1 PLACE CAPS NEAR VCC PIN ON W25Q128 COMPONENT
J 0
(7925 3300);
DISPLAY 1.021277 (7925 3300);
PAINT ORANGE (7925 3300);
FORCEPROP 2 LAST CDS_LIB mstr_symbols
J 0
(8075 3425);
PAINT ORANGE (8075 3425);
DISPLAY INVISIBLE (8075 3425);
FORCEPROP 1 LAST COMMENT_BODY TRUE
J 0
(8100 3525);
DISPLAY 0.978723 (8100 3525);
PAINT ORANGE (8100 3525);
DISPLAY INVISIBLE (8100 3525);
FORCEADD INTEL_CORP_BPAGE..1
(10700 375);
FORCEPROP 1 LAST CDS_CON_LAST_MODIFIED Tue Dec 01 11:52:10 2015
J 0
(9275 700);
PAINT ORANGE (9275 700);
DISPLAY INVISIBLE (9275 700);
FORCEPROP 1 LAST CUSTOM_TXT_CDS <CURRENT_DESIGN_SHEET> OF <TOTAL_DESIGN_SHEETS>
J 0
(10200 400);
PAINT GREEN (10200 400);
FORCEPROP 1 LAST CUSTOM_TXT_CDS <CON_LAST_MODIFIED>
J 0
(8775 725);
PAINT GREEN (8775 725);
FORCEPROP 2 LAST CUSTOM_TXT_CDS <XR_PAGE_TITLE>
J 0
(2810 5625);
DISPLAY 0.638298 (2810 5625);
PAINT PINK (2810 5625);
DISPLAY INVISIBLE (2810 5625);
FORCEPROP 1 LAST SCH_TITLE BMC DEDICATED SPI FLASH
J 0
(2750 425);
DISPLAY 1.212766 (2750 425);
PAINT ORANGE (2750 425);
FORCEPROP 1 LAST SCH_ADDRESS1 2200 Mission College Blvd.
J 0
(6725 500);
DISPLAY 0.617021 (6725 500);
PAINT GREEN (6725 500);
FORCEPROP 1 LAST SCH_ADDRESS2 P.O. BOX 58119
J 0
(6725 450);
DISPLAY 0.617021 (6725 450);
PAINT GREEN (6725 450);
FORCEPROP 1 LAST SCH_ADDRESS3 Santa Clara, CA 95052-8119
J 0
(6725 400);
DISPLAY 0.617021 (6725 400);
PAINT GREEN (6725 400);
FORCEPROP 1 LAST SCH_NUMBER H4694802
J 0
(9400 525);
DISPLAY 1.212766 (9400 525);
PAINT YELLOW (9400 525);
FORCEPROP 1 LAST SCH_DEPT BESD
J 1
(6250 475);
DISPLAY 1.212766 (6250 475);
PAINT YELLOW (6250 475);
FORCEPROP 1 LAST SCH_REV 2.420
J 0
(10450 525);
DISPLAY 0.978723 (10450 525);
PAINT YELLOW (10450 525);
FORCEPROP 2 LAST PAGE_BORDER TRUE
J 0
(2810 5625);
DISPLAY 0.617021 (2810 5625);
PAINT PINK (2810 5625);
DISPLAY INVISIBLE (2810 5625);
FORCEPROP 1 LAST COMMENT_BODY TRUE
J 0
(10712 387);
DISPLAY 0.468085 (10712 387);
PAINT GREEN (10712 387);
DISPLAY INVISIBLE (10712 387);
FORCEPROP 2 LAST CDS_LIB mstr_symbols
J 0
(10700 375);
PAINT MONO (10700 375);
DISPLAY INVISIBLE (10700 375);
FORCEPROP 2 LAST CDS_XR_PAGE_TITLE CR-162 : @BASEBOARD_FAB2_LIB.BASEBOARD_FAB2(SCH_1):PAGE162
J 0
(2810 5625);
DISPLAY 0.638298 (2810 5625);
PAINT PINK (2810 5625);
DISPLAY INVISIBLE (2810 5625);
WIRE 16 -1 (7650 3500)(7650 3550);
WIRE 16 -1 (7650 3550)(7350 3550);
WIRE 16 -1 (7350 3550)(7350 3500);
WIRE 16 -1 (5725 3550)(7350 3550);
WIRE 16 -1 (5725 3550)(5725 3000);
WIRE 16 -1 (5725 3550)(5300 3550);
WIRE 16 -1 (5300 3400)(5300 3550);
WIRE 16 -1 (5100 3550)(5300 3550);
WIRE 16 -1 (5725 3000)(5900 3000);
WIRE 16 -1 (5100 3425)(5100 3550);
WIRE 16 -1 (4900 3550)(5100 3550);
WIRE 16 -1 (4825 3550)(4900 3550);
WIRE 16 -1 (4900 3675)(4900 3550);
WIRE 16 -1 (4550 3550)(4825 3550);
WIRE 16 -1 (4825 3425)(4825 3550);
WIRE 16 -1 (4550 3425)(4550 3550);
WIRE 16 -1 (7650 3200)(7350 3200);
WIRE 16 -1 (7650 3300)(7650 3200);
WIRE 16 -1 (7650 3125)(7650 3200);
WIRE 16 -1 (7350 3200)(7350 3300);
WIRE 16 -1 (4875 1800)(4875 1950);
WIRE 16 -1 (7100 2400)(7100 2550);
WIRE 16 -1 (7100 2550)(7000 2550);
WIRE 16 -1 (4250 2550)(4975 2550);
FORCEPROP 2 LAST SIG_NAME SPI_BMC_BT_DI
J 0
(4250 2560);
DISPLAY 0.617021 (4250 2560);
PAINT ORANGE (4250 2560);
WIRE 16 -1 (5900 2500)(4250 2500);
FORCEPROP 2 LAST SIG_NAME SPI_BMC_BT_DO
J 0
(4250 2510);
DISPLAY 0.617021 (4250 2510);
PAINT ORANGE (4250 2510);
WIRE 16 -1 (5100 2650)(5900 2650);
FORCEPROP 2 LAST SIG_NAME PU_SPI_BMC_BT_HOLD_N
J 0
(5190 2660);
DISPLAY 0.617021 (5190 2660);
PAINT ORANGE (5190 2660);
FORCEPROP 2 LASTPROP $XRERR UNIQUE?
J 0
(4950 2660);
DISPLAY 0.638298 (4950 2660);
PAINT MONO (4950 2660);
DISPLAY INVISIBLE (4950 2660);
WIRE 16 -1 (5100 3225)(5100 2650);
WIRE 16 -1 (4875 2600)(5900 2600);
FORCEPROP 2 LAST SIG_NAME PU_SPI_BMC_BT_WP_N
J 0
(4965 2610);
DISPLAY 0.617021 (4965 2610);
PAINT ORANGE (4965 2610);
FORCEPROP 2 LASTPROP $XRERR UNIQUE?
J 0
(4725 2610);
DISPLAY 0.638298 (4725 2610);
PAINT MONO (4725 2610);
DISPLAY INVISIBLE (4725 2610);
WIRE 16 -1 (4825 2600)(4875 2600);
WIRE 16 -1 (4875 2150)(4875 2600);
WIRE 16 -1 (4825 3225)(4825 2600);
WIRE 16 -1 (4550 3225)(4550 2800);
WIRE 16 -1 (4550 2800)(5900 2800);
WIRE 16 -1 (4250 2800)(4550 2800);
FORCEPROP 2 LAST SIG_NAME SPI_BMC_BT_CS_N
J 0
(4250 2810);
DISPLAY 0.617021 (4250 2810);
PAINT ORANGE (4250 2810);
WIRE 16 -1 (4250 2850)(5900 2850);
FORCEPROP 2 LAST SIG_NAME SPI_BMC_BT_CLK
J 0
(4250 2860);
DISPLAY 0.617021 (4250 2860);
PAINT ORANGE (4250 2860);
WIRE 16 -1 (5900 2550)(5175 2550);
FORCEPROP 2 LAST SIG_NAME SPI_BMC_BT_DI_R
J 2
(5800 2560);
DISPLAY 0.617021 (5800 2560);
PAINT ORANGE (5800 2560);
FORCEPROP 2 LASTPROP $XRERR UNIQUE?
J 0
(5560 2560);
DISPLAY 0.638298 (5560 2560);
PAINT MONO (5560 2560);
DISPLAY INVISIBLE (5560 2560);
WIRE 16 -1 (5300 3200)(5300 2900);
FORCEPROP 2 LAST SIG_NAME PU_SPI_FLASH_RESET_2_N
J 0
(5315 2910);
DISPLAY 0.617021 (5315 2910);
PAINT ORANGE (5315 2910);
FORCEPROP 2 LASTPROP $XRERR UNIQUE?
J 0
(5075 2910);
DISPLAY 0.638298 (5075 2910);
PAINT MONO (5075 2910);
DISPLAY INVISIBLE (5075 2910);
WIRE 16 -1 (5300 2900)(5900 2900);
WIRE 16 -1 (7475 2800)(7000 2800);
FORCEPROP 2 LAST SIG_NAME TP_SPI_2_3
J 0
(7065 2810);
DISPLAY 0.617021 (7065 2810);
PAINT ORANGE (7065 2810);
FORCEPROP 2 LASTPROP $XRERR UNIQUE?
J 0
(7505 2800);
DISPLAY 0.638298 (7505 2800);
PAINT MONO (7505 2800);
DISPLAY INVISIBLE (7505 2800);
WIRE 16 -1 (7475 2850)(7000 2850);
FORCEPROP 2 LAST SIG_NAME TP_SPI_2_4
J 0
(7065 2860);
DISPLAY 0.617021 (7065 2860);
PAINT ORANGE (7065 2860);
FORCEPROP 2 LASTPROP $XRERR UNIQUE?
J 0
(7505 2850);
DISPLAY 0.638298 (7505 2850);
PAINT MONO (7505 2850);
DISPLAY INVISIBLE (7505 2850);
WIRE 16 -1 (7475 2950)(7000 2950);
FORCEPROP 2 LAST SIG_NAME TP_SPI_2_6
J 0
(7065 2960);
DISPLAY 0.617021 (7065 2960);
PAINT ORANGE (7065 2960);
FORCEPROP 2 LASTPROP $XRERR UNIQUE?
J 0
(7505 2950);
DISPLAY 0.638298 (7505 2950);
PAINT MONO (7505 2950);
DISPLAY INVISIBLE (7505 2950);
WIRE 16 -1 (7475 2900)(7000 2900);
FORCEPROP 2 LAST SIG_NAME TP_SPI_2_5
J 0
(7065 2910);
DISPLAY 0.617021 (7065 2910);
PAINT ORANGE (7065 2910);
FORCEPROP 2 LASTPROP $XRERR UNIQUE?
J 0
(7505 2900);
DISPLAY 0.638298 (7505 2900);
PAINT MONO (7505 2900);
DISPLAY INVISIBLE (7505 2900);
WIRE 16 -1 (7475 2750)(7000 2750);
FORCEPROP 2 LAST SIG_NAME TP_SPI_2_2
J 0
(7065 2760);
DISPLAY 0.617021 (7065 2760);
PAINT ORANGE (7065 2760);
FORCEPROP 2 LASTPROP $XRERR UNIQUE?
J 0
(7505 2750);
DISPLAY 0.638298 (7505 2750);
PAINT MONO (7505 2750);
DISPLAY INVISIBLE (7505 2750);
WIRE 16 -1 (7475 2700)(7000 2700);
FORCEPROP 2 LAST SIG_NAME TP_SPI_2_1
J 0
(7065 2710);
DISPLAY 0.617021 (7065 2710);
PAINT ORANGE (7065 2710);
FORCEPROP 2 LASTPROP $XRERR UNIQUE?
J 0
(7505 2700);
DISPLAY 0.638298 (7505 2700);
PAINT MONO (7505 2700);
DISPLAY INVISIBLE (7505 2700);
WIRE 16 -1 (7475 2650)(7000 2650);
FORCEPROP 2 LAST SIG_NAME TP_SPI_2_0
J 0
(7065 2660);
DISPLAY 0.617021 (7065 2660);
PAINT ORANGE (7065 2660);
FORCEPROP 2 LASTPROP $XRERR UNIQUE?
J 0
(7505 2650);
DISPLAY 0.638298 (7505 2650);
PAINT MONO (7505 2650);
DISPLAY INVISIBLE (7505 2650);
DOT 1 (7650 3200);
DOT 1 (7350 3550);
DOT 1 (5725 3550);
DOT 1 (5300 3550);
DOT 1 (5100 3550);
DOT 1 (4900 3550);
DOT 1 (4825 3550);
DOT 1 (4875 2600);
DOT 1 (4550 2800);
QUIT
